# T6G (Grand Teton) — schematic netlist excerpt (pin names and nets, part order shuffled) for the footprints in the layout excerpt that follows; sources: Cadence DE-HDL packaged netlist, KiCad conversion of 04192023_DAF0TMB3IC0_F0TG_MB_C_brd_V02_OCP.brd

J37  SCONN288_DDR506112002KQ  IO  pkg DDR288S_1-1VXC  page 109
  VIN_BULK0  = P12V_MEM_CPU1
  RFU0  = NC
  VIN_MGMT  = P3V3_AUX
  HSCL  = I3C_SPD_DDRL_CPU1_SCL
  HSDA  = I3C_SPD_DDRL_CPU1_SDA
  VSS0  = GND
  DQ0_A  = M_L_CPU1_SA_DQ<0>
  VSS1  = GND
  DQ1_A  = M_L_CPU1_SA_DQ<1>
  VSS2  = GND
  DQS0_A_T  = M_L_CPU1_SA_DQS_DP<0>
  DQS0_A_C  = M_L_CPU1_SA_DQS_DN<0>
  VSS3  = GND
  DQ4_A  = M_L_CPU1_SA_DQ<4>
  VSS4  = GND
  DQ5_A  = M_L_CPU1_SA_DQ<5>
  VSS5  = GND
  DQ8_A  = M_L_CPU1_SA_DQ<8>
  VSS6  = GND
  DQ9_A  = M_L_CPU1_SA_DQ<9>
  VSS7  = GND
  DQS1_A_T  = M_L_CPU1_SA_DQS_DP<1>
  DQS1_A_C  = M_L_CPU1_SA_DQS_DN<1>
  VSS8  = GND
  DQ12_A  = M_L_CPU1_SA_DQ<12>
  VSS9  = GND
  DQ13_A  = M_L_CPU1_SA_DQ<13>
  VSS10  = GND
  DQ16_A  = M_L_CPU1_SA_DQ<16>
  VSS11  = GND
  DQ17_A  = M_L_CPU1_SA_DQ<17>
  VSS12  = GND
  DQS2_A_T  = M_L_CPU1_SA_DQS_DP<2>
  DQS2_A_C  = M_L_CPU1_SA_DQS_DN<2>
  VSS13  = GND
  DQ20_A  = M_L_CPU1_SA_DQ<20>
  VSS14  = GND
  DQ21_A  = M_L_CPU1_SA_DQ<21>
  VSS15  = GND
  DQ24_A  = M_L_CPU1_SA_DQ<24>
  VSS16  = GND
  DQ25_A  = M_L_CPU1_SA_DQ<25>
  VSS17  = GND
  DQS3_A_T  = M_L_CPU1_SA_DQS_DP<3>
  DQS3_A_C  = M_L_CPU1_SA_DQS_DN<3>
  VSS18  = GND
  DQ28_A  = M_L_CPU1_SA_DQ<28>
  VSS19  = GND
  DQ29_A  = M_L_CPU1_SA_DQ<29>
  VSS20  = GND
  CB0_A  = M_L_CPU1_SA_CB<0>
  VSS21  = GND
  CB1_A  = M_L_CPU1_SA_CB<1>
  VSS22  = GND
  DQS4_A_T  = M_L_CPU1_SA_DQS_DP<4>
  DQS4_A_C  = M_L_CPU1_SA_DQS_DN<4>
  VSS23  = GND
  CB4_A  = M_L_CPU1_SA_CB<4>
  VSS24  = GND
  CB5_A  = M_L_CPU1_SA_CB<5>
  VSS25  = GND
  ALERT_N  = M_L_CPU1_ALERT_N
  VSS26  = GND
  CS0_A_N  = M_L_CPU1_SA_CS_N<0>
  VSS27  = GND
  CA0_A  = M_L_CPU1_SA_CA<0>
  VSS28  = GND
  CA2_A  = M_L_CPU1_SA_CA<2>
  VSS29  = GND
  CA4_A  = M_L_CPU1_SA_CA<4>
  VSS30  = GND
  CA6_A  = M_L_CPU1_SA_CA<6>
  VSS31  = GND
  PAR_A  = M_L_CPU1_SA_PAR
  VSS32  = GND
  CA0_B  = M_L_CPU1_SB_CA<0>
  VSS33  = GND
  CA2_B  = M_L_CPU1_SB_CA<2>
  VSS34  = GND
  CA4_B  = M_L_CPU1_SB_CA<4>
  VSS35  = GND
  CA6_B  = M_L_CPU1_SB_CA<6>
  VSS36  = GND
  CS0_B_N  = M_L_CPU1_SB_CS_N<0>
  VSS37  = GND
  \lbd||rsp_a_n\  = M_L_CPU1_SA_RSP<0>
  \lbs||rsp_b_n\  = M_L_CPU1_SB_RSP<0>
  VSS38  = GND
  CB4_B  = M_L_CPU1_SB_CB<4>
  VSS39  = GND
  CB5_B  = M_L_CPU1_SB_CB<5>
  VSS40  = GND
  \dqs9_b_t||tdqs9_b_t||dbi4_b_n\  = M_L_CPU1_SB_DQS_DP<9>
  \dqs9_b_c||tdqs9_b_c\  = M_L_CPU1_SB_DQS_DN<9>
  VSS41  = GND
  CB0_B  = M_L_CPU1_SB_CB<0>
  VSS42  = GND
  CB1_B  = M_L_CPU1_SB_CB<1>
  VSS43  = GND
  DQ0_B  = M_L_CPU1_SB_DQ<0>
  VSS44  = GND
  DQ1_B  = M_L_CPU1_SB_DQ<1>
  VSS45  = GND
  DQS0_B_T  = M_L_CPU1_SB_DQS_DP<0>
  DQS0_B_C  = M_L_CPU1_SB_DQS_DN<0>
  VSS46  = GND
  DQ4_B  = M_L_CPU1_SB_DQ<4>
  VSS47  = GND
  DQ5_B  = M_L_CPU1_SB_DQ<5>
  VSS48  = GND
  DQ8_B  = M_L_CPU1_SB_DQ<8>
  VSS49  = GND
  DQ9_B  = M_L_CPU1_SB_DQ<9>
  VSS50  = GND
  DQS1_B_T  = M_L_CPU1_SB_DQS_DP<1>
  DQS1_B_C  = M_L_CPU1_SB_DQS_DN<1>
  VSS51  = GND
  DQ12_B  = M_L_CPU1_SB_DQ<12>
  VSS52  = GND
  DQ13_B  = M_L_CPU1_SB_DQ<13>
  VSS53  = GND
  DQ16_B  = M_L_CPU1_SB_DQ<16>
  VSS54  = GND
  DQ17_B  = M_L_CPU1_SB_DQ<17>
  VSS55  = GND
  DQS2_B_T  = M_L_CPU1_SB_DQS_DP<2>
  DQS2_B_C  = M_L_CPU1_SB_DQS_DN<2>
  VSS56  = GND
  DQ20_B  = M_L_CPU1_SB_DQ<20>
  VSS57  = GND
  DQ21_B  = M_L_CPU1_SB_DQ<21>
  VSS58  = GND
  DQ24_B  = M_L_CPU1_SB_DQ<24>
  VSS59  = GND
  DQ25_B  = M_L_CPU1_SB_DQ<25>
  VSS60  = GND
  DQS3_B_T  = M_L_CPU1_SB_DQS_DP<3>
  DQS3_B_C  = M_L_CPU1_SB_DQS_DN<3>
  VSS61  = GND
  DQ28_B  = M_L_CPU1_SB_DQ<28>
  VSS62  = GND
  DQ29_B  = M_L_CPU1_SB_DQ<29>
  VSS63  = GND
  RFU1  = NC
  VIN_BULK1  = P12V_MEM_CPU1
  VIN_BULK2  = P12V_MEM_CPU1
  \pwr_good||fail_n\  = PWRGD_CHL_CPU1_DIMM
  HAS  = PD_CHL_CPU1_DIMM_SAA
  RFU2  = NC
  RFU3  = NC
  VSS64  = GND
  DQ2_A  = M_L_CPU1_SA_DQ<2>
  VSS65  = GND
  DQ3_A  = M_L_CPU1_SA_DQ<3>
  VSS66  = GND
  \dqs5_a_c||tdqs5_a_c||dqs5_a_t||tdqs5_a_t\  = M_L_CPU1_SA_DQS_DN<5>
  \dqs5_a_t||tdqs5_a_t\  = M_L_CPU1_SA_DQS_DP<5>
  VSS67  = GND
  DQ6_A  = M_L_CPU1_SA_DQ<6>
  VSS68  = GND
  DQ7_A  = M_L_CPU1_SA_DQ<7>
  VSS69  = GND
  DQ10_A  = M_L_CPU1_SA_DQ<10>
  VSS70  = GND
  DQ11_A  = M_L_CPU1_SA_DQ<11>
  VSS71  = GND
  \dqs6_a_c||tdqs6_a_c||dqs6_a_t||tdqs6_a_t\  = M_L_CPU1_SA_DQS_DN<6>
  \dqs6_a_t||tdqs6_a_t\  = M_L_CPU1_SA_DQS_DP<6>
  VSS72  = GND
  DQ14_A  = M_L_CPU1_SA_DQ<14>
  VSS73  = GND
  DQ15_A  = M_L_CPU1_SA_DQ<15>
  VSS74  = GND
  DQ18_A  = M_L_CPU1_SA_DQ<18>
  VSS75  = GND
  DQ19_A  = M_L_CPU1_SA_DQ<19>
  VSS76  = GND
  \dqs7_a_c||tdqs7_a_c\  = M_L_CPU1_SA_DQS_DN<7>
  \dqs7_a_t||tdqs7_a_t\  = M_L_CPU1_SA_DQS_DP<7>
  VSS77  = GND
  DQ22_A  = M_L_CPU1_SA_DQ<22>
  VSS78  = GND
  DQ23_A  = M_L_CPU1_SA_DQ<23>
  VSS79  = GND
  DQ26_A  = M_L_CPU1_SA_DQ<26>
  VSS80  = GND
  DQ27_A  = M_L_CPU1_SA_DQ<27>
  VSS81  = GND
  \dqs8_a_c||tdqs8_a_c\  = M_L_CPU1_SA_DQS_DN<8>
  \dqs8_a_t||tdqs8_a_t\  = M_L_CPU1_SA_DQS_DP<8>
  VSS82  = GND
  DQ30_A  = M_L_CPU1_SA_DQ<30>
  VSS83  = GND
  DQ31_A  = M_L_CPU1_SA_DQ<31>
  VSS84  = GND
  CB2_A  = M_L_CPU1_SA_CB<2>
  VSS85  = GND
  CB3_A  = M_L_CPU1_SA_CB<3>
  VSS86  = GND
  \dqs9_a_c||tdqs9_a_c\  = M_L_CPU1_SA_DQS_DN<9>
  \dqs9_a_t||tdqs9_a_t\  = M_L_CPU1_SA_DQS_DP<9>
  VSS87  = GND
  CB6_A  = M_L_CPU1_SA_CB<6>
  VSS88  = GND
  CB7_A  = M_L_CPU1_SA_CB<7>
  VSS89  = GND
  RESET_N  = M_L_CPU1_RESET_N
  VSS90  = GND
  CS1_A_N  = M_L_CPU1_SA_CS_N<1>
  VSS91  = GND
  CA1_A  = M_L_CPU1_SA_CA<1>
  VSS92  = GND
  CA3_A  = M_L_CPU1_SA_CA<3>
  VSS93  = GND
  CA5_A  = M_L_CPU1_SA_CA<5>
  VSS94  = GND
  CK_T  = M_L_CPU1_CLK_DP<0>
  CK_C  = M_L_CPU1_CLK_DN<0>
  VSS95  = GND
  RFU4  = NC
  CA1_B  = M_L_CPU1_SB_CA<1>
  VSS96  = GND
  CA3_B  = M_L_CPU1_SB_CA<3>
  VSS97  = GND
  CA5_B  = M_L_CPU1_SB_CA<5>
  VSS98  = GND
  PAR_B  = M_L_CPU1_SB_PAR
  VSS99  = GND
  CS1_B_N  = M_L_CPU1_SB_CS_N<1>
  VSS100  = GND
  RFU5  = NC
  RFU6  = NC
  VSS101  = GND
  CB6_B  = M_L_CPU1_SB_CB<6>
  VSS102  = GND
  CB7_B  = M_L_CPU1_SB_CB<7>
  VSS103  = GND
  DQS4_B_C  = M_L_CPU1_SB_DQS_DN<4>
  DQS4_B_T  = M_L_CPU1_SB_DQS_DP<4>
  VSS104  = GND
  CB2_B  = M_L_CPU1_SB_CB<2>
  VSS105  = GND
  CB3_B  = M_L_CPU1_SB_CB<3>
  VSS106  = GND
  DQ2_B  = M_L_CPU1_SB_DQ<2>
  VSS107  = GND
  DQ3_B  = M_L_CPU1_SB_DQ<3>
  VSS108  = GND
  \dqs5_b_c||tdqs5_b_c\  = M_L_CPU1_SB_DQS_DN<5>
  \dqs5_b_t||tdqs5_b_t\  = M_L_CPU1_SB_DQS_DP<5>
  VSS109  = GND
  DQ6_B  = M_L_CPU1_SB_DQ<6>
  VSS110  = GND
  DQ7_B  = M_L_CPU1_SB_DQ<7>
  VSS111  = GND
  DQ10_B  = M_L_CPU1_SB_DQ<10>
  VSS112  = GND
  DQ11_B  = M_L_CPU1_SB_DQ<11>
  VSS113  = GND
  \dqs6_b_c||tdqs6_b_c\  = M_L_CPU1_SB_DQS_DN<6>
  \dqs6_b_t||tdqs6_b_t\  = M_L_CPU1_SB_DQS_DP<6>
  VSS114  = GND
  DQ14_B  = M_L_CPU1_SB_DQ<14>
  VSS115  = GND
  DQ15_B  = M_L_CPU1_SB_DQ<15>
  VSS116  = GND
  DQ18_B  = M_L_CPU1_SB_DQ<18>
  VSS117  = GND
  DQ19_B  = M_L_CPU1_SB_DQ<19>
  VSS118  = GND
  \dqs7_b_c||tdqs7_b_c\  = M_L_CPU1_SB_DQS_DN<7>
  \dqs7_b_t||tdqs7_b_t\  = M_L_CPU1_SB_DQS_DP<7>
  VSS119  = GND
  DQ22_B  = M_L_CPU1_SB_DQ<22>
  VSS120  = GND
  DQ23_B  = M_L_CPU1_SB_DQ<23>
  VSS121  = GND
  DQ26_B  = M_L_CPU1_SB_DQ<26>
  VSS122  = GND
  DQ27_B  = M_L_CPU1_SB_DQ<27>
  VSS123  = GND
  \dqs8_b_c||tdqs8_b_c\  = M_L_CPU1_SB_DQS_DN<8>
  \dqs8_b_t||tdqs8_b_t\  = M_L_CPU1_SB_DQS_DP<8>
  VSS124  = GND
  DQ30_B  = M_L_CPU1_SB_DQ<30>
  VSS125  = GND
  DQ31_B  = M_L_CPU1_SB_DQ<31>
  VSS126  = GND
  G1  = GND
  G2  = GND
  G3  = GND

(kicad_pcb
	(version 20260206)
	(generator "pcbnew")
	(generator_version "10.0")
	(general
		(thickness 1.6)
		(legacy_teardrops no)
	)
	(paper "A4")
	(title_block
		(title "04192023_DAF0TMB3IC0_F0TG_MB_C_brd_V02_OCP.brd")
		(comment 1 "Grand Teton / footprint 34 of 8354 (J37), pads 231-276 of 291")
	)
	(layers
		(0 "F.Cu" signal "TOP")
		(4 "In1.Cu" signal "GND")
		(6 "In2.Cu" signal "IN1")
		(8 "In3.Cu" signal "GND1")
		(10 "In4.Cu" signal "IN2")
		(12 "In5.Cu" signal "GND2")
		(14 "In6.Cu" signal "IN3")
		(16 "In7.Cu" signal "GND3")
		(18 "In8.Cu" signal "VCC")
		(20 "In9.Cu" signal "VCC1")
		(22 "In10.Cu" signal "GND4")
		(24 "In11.Cu" signal "IN4")
		(26 "In12.Cu" signal "GND5")
		(28 "In13.Cu" signal "IN5")
		(30 "In14.Cu" signal "GND6")
		(32 "In15.Cu" signal "IN6")
		(34 "In16.Cu" signal "GND7")
		(2 "B.Cu" signal "BOTTOM")
		(9 "F.Adhes" user "F.Adhesive")
		(11 "B.Adhes" user "B.Adhesive")
		(13 "F.Paste" user "Package Geometry/Pastemask Top")
		(15 "B.Paste" user "Package Geometry/Pastemask Bottom")
		(5 "F.SilkS" user "Ref Des/Silkscreen Top")
		(7 "B.SilkS" user "Ref Des/Silkscreen Bottom")
		(1 "F.Mask" user "Board Geometry/Soldermask Top")
		(3 "B.Mask" user "Board Geometry/Soldermask Bottom")
		(17 "Dwgs.User" user "User.Drawings")
		(19 "Cmts.User" user "User.Comments")
		(21 "Eco1.User" user "User.Eco1")
		(23 "Eco2.User" user "User.Eco2")
		(25 "Edge.Cuts" user "Board Geometry/Outline")
		(27 "Margin" user)
		(31 "F.CrtYd" user "Package Geometry/Place Bound Top")
		(29 "B.CrtYd" user "Package Geometry/Place Bound Bottom")
		(35 "F.Fab" user "Ref Des/Assembly Top")
		(33 "B.Fab" user "Ref Des/Assembly Bottom")
	)
	(footprint ""
		(layer "F.Cu")
		(at 204.197966 -255.560322 180)
		(property "Reference" "J37"
			(at 2.8702 -81.730088 0)
			(unlocked yes)
			(layer "F.SilkS")
			(effects
				(font
					(size 0.7874 0.5842)
					(thickness 0.1524)
				)
			)
		)
		(property "Value" ""
			(at 0 0 180)
			(layer "F.Fab")
			(effects
				(font
					(size 1.27 1.27)
				)
			)
		)
		(duplicate_pad_numbers_are_jumpers no)
		(pad "231" smd rect
			(at 2.050034 14.875002 90)
			(size 0.519938 1.4986)
			(layers "F.Cu" "F.Mask" "F.Paste")
			(net "Net_2415")
		)
		(pad "232" smd rect
			(at 2.050034 15.724886 90)
			(size 0.519938 1.4986)
			(layers "F.Cu" "F.Mask" "F.Paste")
			(net "Net_2416")
		)
		(pad "233" smd rect
			(at 2.050034 16.575024 90)
			(size 0.519938 1.4986)
			(layers "F.Cu" "F.Mask" "F.Paste")
			(net "GND")
		)
		(pad "234" smd rect
			(at 2.050034 17.424908 90)
			(size 0.519938 1.4986)
			(layers "F.Cu" "F.Mask" "F.Paste")
			(net "M_L_CPU1_SB_CB<6>")
		)
		(pad "235" smd rect
			(at 2.050034 18.275046 90)
			(size 0.519938 1.4986)
			(layers "F.Cu" "F.Mask" "F.Paste")
			(net "GND")
		)
		(pad "236" smd rect
			(at 2.050034 19.12493 90)
			(size 0.519938 1.4986)
			(layers "F.Cu" "F.Mask" "F.Paste")
			(net "M_L_CPU1_SB_CB<7>")
		)
		(pad "237" smd rect
			(at 2.050034 19.975068 90)
			(size 0.519938 1.4986)
			(layers "F.Cu" "F.Mask" "F.Paste")
			(net "GND")
		)
		(pad "238" smd rect
			(at 2.050034 20.824952 90)
			(size 0.519938 1.4986)
			(layers "F.Cu" "F.Mask" "F.Paste")
			(net "M_L_CPU1_SB_DQS_DN<4>")
		)
		(pad "239" smd rect
			(at 2.050034 21.67509 90)
			(size 0.519938 1.4986)
			(layers "F.Cu" "F.Mask" "F.Paste")
			(net "M_L_CPU1_SB_DQS_DP<4>")
		)
		(pad "240" smd rect
			(at 2.050034 22.524974 90)
			(size 0.519938 1.4986)
			(layers "F.Cu" "F.Mask" "F.Paste")
			(net "GND")
		)
		(pad "241" smd rect
			(at 2.050034 23.375112 90)
			(size 0.519938 1.4986)
			(layers "F.Cu" "F.Mask" "F.Paste")
			(net "M_L_CPU1_SB_CB<2>")
		)
		(pad "242" smd rect
			(at 2.050034 24.224996 90)
			(size 0.519938 1.4986)
			(layers "F.Cu" "F.Mask" "F.Paste")
			(net "GND")
		)
		(pad "243" smd rect
			(at 2.050034 25.07488 90)
			(size 0.519938 1.4986)
			(layers "F.Cu" "F.Mask" "F.Paste")
			(net "M_L_CPU1_SB_CB<3>")
		)
		(pad "244" smd rect
			(at 2.050034 25.925018 90)
			(size 0.519938 1.4986)
			(layers "F.Cu" "F.Mask" "F.Paste")
			(net "GND")
		)
		(pad "245" smd rect
			(at 2.050034 26.774902 90)
			(size 0.519938 1.4986)
			(layers "F.Cu" "F.Mask" "F.Paste")
			(net "M_L_CPU1_SB_DQ<2>")
		)
		(pad "246" smd rect
			(at 2.050034 27.62504 90)
			(size 0.519938 1.4986)
			(layers "F.Cu" "F.Mask" "F.Paste")
			(net "GND")
		)
		(pad "247" smd rect
			(at 2.050034 28.474924 90)
			(size 0.519938 1.4986)
			(layers "F.Cu" "F.Mask" "F.Paste")
			(net "M_L_CPU1_SB_DQ<3>")
		)
		(pad "248" smd rect
			(at 2.050034 29.325062 90)
			(size 0.519938 1.4986)
			(layers "F.Cu" "F.Mask" "F.Paste")
			(net "GND")
		)
		(pad "249" smd rect
			(at 2.050034 30.174946 90)
			(size 0.519938 1.4986)
			(layers "F.Cu" "F.Mask" "F.Paste")
			(net "M_L_CPU1_SB_DQS_DN<5>")
		)
		(pad "250" smd rect
			(at 2.050034 31.025084 90)
			(size 0.519938 1.4986)
			(layers "F.Cu" "F.Mask" "F.Paste")
			(net "M_L_CPU1_SB_DQS_DP<5>")
		)
		(pad "251" smd rect
			(at 2.050034 31.874968 90)
			(size 0.519938 1.4986)
			(layers "F.Cu" "F.Mask" "F.Paste")
			(net "GND")
		)
		(pad "252" smd rect
			(at 2.050034 32.725106 90)
			(size 0.519938 1.4986)
			(layers "F.Cu" "F.Mask" "F.Paste")
			(net "M_L_CPU1_SB_DQ<6>")
		)
		(pad "253" smd rect
			(at 2.050034 33.57499 90)
			(size 0.519938 1.4986)
			(layers "F.Cu" "F.Mask" "F.Paste")
			(net "GND")
		)
		(pad "254" smd rect
			(at 2.050034 34.425128 90)
			(size 0.519938 1.4986)
			(layers "F.Cu" "F.Mask" "F.Paste")
			(net "M_L_CPU1_SB_DQ<7>")
		)
		(pad "255" smd rect
			(at 2.050034 35.275012 90)
			(size 0.519938 1.4986)
			(layers "F.Cu" "F.Mask" "F.Paste")
			(net "GND")
		)
		(pad "256" smd rect
			(at 2.050034 36.124896 90)
			(size 0.519938 1.4986)
			(layers "F.Cu" "F.Mask" "F.Paste")
			(net "M_L_CPU1_SB_DQ<10>")
		)
		(pad "257" smd rect
			(at 2.050034 36.975034 90)
			(size 0.519938 1.4986)
			(layers "F.Cu" "F.Mask" "F.Paste")
			(net "GND")
		)
		(pad "258" smd rect
			(at 2.050034 37.824918 90)
			(size 0.519938 1.4986)
			(layers "F.Cu" "F.Mask" "F.Paste")
			(net "M_L_CPU1_SB_DQ<11>")
		)
		(pad "259" smd rect
			(at 2.050034 38.675056 90)
			(size 0.519938 1.4986)
			(layers "F.Cu" "F.Mask" "F.Paste")
			(net "GND")
		)
		(pad "260" smd rect
			(at 2.050034 39.52494 90)
			(size 0.519938 1.4986)
			(layers "F.Cu" "F.Mask" "F.Paste")
			(net "M_L_CPU1_SB_DQS_DN<6>")
		)
		(pad "261" smd rect
			(at 2.050034 40.375078 90)
			(size 0.519938 1.4986)
			(layers "F.Cu" "F.Mask" "F.Paste")
			(net "M_L_CPU1_SB_DQS_DP<6>")
		)
		(pad "262" smd rect
			(at 2.050034 41.224962 90)
			(size 0.519938 1.4986)
			(layers "F.Cu" "F.Mask" "F.Paste")
			(net "GND")
		)
		(pad "263" smd rect
			(at 2.050034 42.0751 90)
			(size 0.519938 1.4986)
			(layers "F.Cu" "F.Mask" "F.Paste")
			(net "M_L_CPU1_SB_DQ<14>")
		)
		(pad "264" smd rect
			(at 2.050034 42.924984 90)
			(size 0.519938 1.4986)
			(layers "F.Cu" "F.Mask" "F.Paste")
			(net "GND")
		)
		(pad "265" smd rect
			(at 2.050034 43.775122 90)
			(size 0.519938 1.4986)
			(layers "F.Cu" "F.Mask" "F.Paste")
			(net "M_L_CPU1_SB_DQ<15>")
		)
		(pad "266" smd rect
			(at 2.050034 44.625006 90)
			(size 0.519938 1.4986)
			(layers "F.Cu" "F.Mask" "F.Paste")
			(net "GND")
		)
		(pad "267" smd rect
			(at 2.050034 45.47489 90)
			(size 0.519938 1.4986)
			(layers "F.Cu" "F.Mask" "F.Paste")
			(net "M_L_CPU1_SB_DQ<18>")
		)
		(pad "268" smd rect
			(at 2.050034 46.325028 90)
			(size 0.519938 1.4986)
			(layers "F.Cu" "F.Mask" "F.Paste")
			(net "GND")
		)
		(pad "269" smd rect
			(at 2.050034 47.174912 90)
			(size 0.519938 1.4986)
			(layers "F.Cu" "F.Mask" "F.Paste")
			(net "M_L_CPU1_SB_DQ<19>")
		)
		(pad "270" smd rect
			(at 2.050034 48.02505 90)
			(size 0.519938 1.4986)
			(layers "F.Cu" "F.Mask" "F.Paste")
			(net "GND")
		)
		(pad "271" smd rect
			(at 2.050034 48.874934 90)
			(size 0.519938 1.4986)
			(layers "F.Cu" "F.Mask" "F.Paste")
			(net "M_L_CPU1_SB_DQS_DN<7>")
		)
		(pad "272" smd rect
			(at 2.050034 49.725072 90)
			(size 0.519938 1.4986)
			(layers "F.Cu" "F.Mask" "F.Paste")
			(net "M_L_CPU1_SB_DQS_DP<7>")
		)
		(pad "273" smd rect
			(at 2.050034 50.574956 90)
			(size 0.519938 1.4986)
			(layers "F.Cu" "F.Mask" "F.Paste")
			(net "GND")
		)
		(pad "274" smd rect
			(at 2.050034 51.425094 90)
			(size 0.519938 1.4986)
			(layers "F.Cu" "F.Mask" "F.Paste")
			(net "M_L_CPU1_SB_DQ<22>")
		)
		(pad "275" smd rect
			(at 2.050034 52.274978 90)
			(size 0.519938 1.4986)
			(layers "F.Cu" "F.Mask" "F.Paste")
			(net "GND")
		)
		(pad "276" smd rect
			(at 2.050034 53.125116 90)
			(size 0.519938 1.4986)
			(layers "F.Cu" "F.Mask" "F.Paste")
			(net "M_L_CPU1_SB_DQ<23>")
		)
	)
)
